(kicad_pcb
	(version 20260206)
	(generator "pcbnew")
	(generator_version "10.0")
	(general
		(thickness 1.6)
		(legacy_teardrops no)
	)
	(paper "A4")
	(title_block
		(title "Wiwynn_Tioga_Pass_MB.brd")
		(comment 1 "Tioga Pass / footprints 3086-3092 of 4770")
	)
	(layers
		(0 "F.Cu" signal "TOP")
		(4 "In1.Cu" signal "L2GND")
		(6 "In2.Cu" signal "L3")
		(8 "In3.Cu" signal "L4GND")
		(10 "In4.Cu" signal "L5")
		(12 "In5.Cu" signal "L6GND")
		(14 "In6.Cu" signal "L7VCC")
		(16 "In7.Cu" signal "L8VCC")
		(18 "In8.Cu" signal "L9GND")
		(20 "In9.Cu" signal "L10")
		(22 "In10.Cu" signal "L11GND")
		(24 "In11.Cu" signal "L12")
		(26 "In12.Cu" signal "L13GND")
		(2 "B.Cu" signal "BOTTOM")
		(9 "F.Adhes" user "F.Adhesive")
		(11 "B.Adhes" user "B.Adhesive")
		(13 "F.Paste" user "Package Geometry/Pastemask Top")
		(15 "B.Paste" user "Package Geometry/Pastemask Bottom")
		(5 "F.SilkS" user "Ref Des/Silkscreen Top")
		(7 "B.SilkS" user "Ref Des/Silkscreen Bottom")
		(1 "F.Mask" user "Board Geometry/Soldermask Top")
		(3 "B.Mask" user "Board Geometry/Soldermask Bottom")
		(17 "Dwgs.User" user "User.Drawings")
		(19 "Cmts.User" user "User.Comments")
		(21 "Eco1.User" user "User.Eco1")
		(23 "Eco2.User" user "User.Eco2")
		(25 "Edge.Cuts" user "Board Geometry/Outline")
		(27 "Margin" user)
		(31 "F.CrtYd" user "Package Geometry/Place Bound Top")
		(29 "B.CrtYd" user "Package Geometry/Place Bound Bottom")
		(35 "F.Fab" user "Ref Des/Assembly Top")
		(33 "B.Fab" user "Ref Des/Assembly Bottom")
	)
	(footprint ""
		(layer "B.Cu")
		(at 376.174 -88.0745)
		(property "Reference" "R7C21"
			(at 0.8382 -0.67818 0)
			(unlocked yes)
			(layer "B.SilkS")
			(effects
				(font
					(size 0.4064 0.254)
					(thickness 0.1524)
				)
				(justify left mirror)
			)
		)
		(property "Value" ""
			(at 0 0 0)
			(layer "B.Fab")
			(effects
				(font
					(size 1.27 1.27)
				)
				(justify mirror)
			)
		)
		(duplicate_pad_numbers_are_jumpers no)
		(fp_poly
			(pts
				(xy 0.2794 -0.1016) (xy -0.2794 -0.1016) (xy -0.2794 0.9906) (xy 0.2794 0.9906)
			)
			(stroke
				(width 0)
				(type default)
			)
			(fill no)
			(layer "B.CrtYd")
		)
		(fp_line
			(start -0.2794 -0.1016)
			(end 0.2794 -0.1016)
			(stroke
				(width 0.1)
				(type default)
			)
			(layer "B.Fab")
		)
		(fp_line
			(start -0.2794 0.9906)
			(end -0.2794 -0.1016)
			(stroke
				(width 0.1)
				(type default)
			)
			(layer "B.Fab")
		)
		(fp_line
			(start 0.2794 -0.1016)
			(end 0.2794 0.9906)
			(stroke
				(width 0.1)
				(type default)
			)
			(layer "B.Fab")
		)
		(fp_line
			(start 0.2794 0.9906)
			(end -0.2794 0.9906)
			(stroke
				(width 0.1)
				(type default)
			)
			(layer "B.Fab")
		)
		(pad "1" smd rect
			(at 0 0 180)
			(size 0.508 0.508)
			(layers "B.Cu" "B.Mask" "B.Paste")
			(net "P1V05_PCH_STBY")
		)
		(pad "2" smd rect
			(at 0 0.889 180)
			(size 0.508 0.508)
			(layers "B.Cu" "B.Mask" "B.Paste")
			(net "FM_PCH_LVC1_THERMTRIP_N")
		)
		(zone
			(layer "B.Cu")
			(hatch none 0.5)
			(connect_pads
				(clearance 0)
			)
			(min_thickness 0.25)
			(keepout
				(tracks allowed)
				(vias not_allowed)
				(pads allowed)
				(copperpour not_allowed)
				(footprints allowed)
			)
			(placement
				(enabled no)
				(sheetname "")
			)
			(fill
				(thermal_gap 0.5)
				(thermal_bridge_width 0.5)
				(island_removal_mode 0)
			)
			(polygon
				(pts
					(xy 376.428 -87.8205) (xy 375.92 -87.8205) (xy 375.92 -87.4395) (xy 376.428 -87.4395)
				)
			)
		)
		(zone
			(layer "B.Cu")
			(hatch none 0.5)
			(connect_pads
				(clearance 0)
			)
			(min_thickness 0.25)
			(keepout
				(tracks not_allowed)
				(vias allowed)
				(pads allowed)
				(copperpour not_allowed)
				(footprints allowed)
			)
			(placement
				(enabled no)
				(sheetname "")
			)
			(fill
				(thermal_gap 0.5)
				(thermal_bridge_width 0.5)
				(island_removal_mode 0)
			)
			(polygon
				(pts
					(xy 376.428 -87.4395) (xy 375.92 -87.4395) (xy 375.92 -87.8205) (xy 376.428 -87.8205)
				)
			)
		)
	)
	(footprint ""
		(layer "B.Cu")
		(at 316.2808 -120.3198 90)
		(property "Reference" "R3R12"
			(at 0 0 90)
			(layer "B.SilkS")
			(hide yes)
			(effects
				(font
					(size 1.27 1.27)
				)
				(justify mirror)
			)
		)
		(property "Value" ""
			(at 0 0 90)
			(layer "B.Fab")
			(effects
				(font
					(size 1.27 1.27)
				)
				(justify mirror)
			)
		)
		(duplicate_pad_numbers_are_jumpers no)
		(fp_poly
			(pts
				(xy 0.2794 -0.1016) (xy -0.2794 -0.1016) (xy -0.2794 0.9906) (xy 0.2794 0.9906)
			)
			(stroke
				(width 0)
				(type default)
			)
			(fill no)
			(layer "B.CrtYd")
		)
		(fp_line
			(start 0.2794 -0.1016)
			(end 0.2794 0.9906)
			(stroke
				(width 0.1)
				(type default)
			)
			(layer "B.Fab")
		)
		(fp_line
			(start -0.2794 -0.1016)
			(end 0.2794 -0.1016)
			(stroke
				(width 0.1)
				(type default)
			)
			(layer "B.Fab")
		)
		(fp_line
			(start 0.2794 0.9906)
			(end -0.2794 0.9906)
			(stroke
				(width 0.1)
				(type default)
			)
			(layer "B.Fab")
		)
		(fp_line
			(start -0.2794 0.9906)
			(end -0.2794 -0.1016)
			(stroke
				(width 0.1)
				(type default)
			)
			(layer "B.Fab")
		)
		(pad "1" smd rect
			(at 0 0 270)
			(size 0.508 0.508)
			(layers "B.Cu" "B.Mask" "B.Paste")
			(net "PVPP_DEF")
		)
		(pad "2" smd rect
			(at 0 0.889 270)
			(size 0.508 0.508)
			(layers "B.Cu" "B.Mask" "B.Paste")
			(net "SMB_DDR_DEF_VPP_SDA_R")
		)
		(zone
			(layer "B.Cu")
			(hatch none 0.5)
			(connect_pads
				(clearance 0)
			)
			(min_thickness 0.25)
			(keepout
				(tracks allowed)
				(vias not_allowed)
				(pads allowed)
				(copperpour not_allowed)
				(footprints allowed)
			)
			(placement
				(enabled no)
				(sheetname "")
			)
			(fill
				(thermal_gap 0.5)
				(thermal_bridge_width 0.5)
				(island_removal_mode 0)
			)
			(polygon
				(pts
					(xy 316.5348 -120.5738) (xy 316.5348 -120.0658) (xy 316.9158 -120.0658) (xy 316.9158 -120.5738)
				)
			)
		)
		(zone
			(layer "B.Cu")
			(hatch none 0.5)
			(connect_pads
				(clearance 0)
			)
			(min_thickness 0.25)
			(keepout
				(tracks not_allowed)
				(vias allowed)
				(pads allowed)
				(copperpour not_allowed)
				(footprints allowed)
			)
			(placement
				(enabled no)
				(sheetname "")
			)
			(fill
				(thermal_gap 0.5)
				(thermal_bridge_width 0.5)
				(island_removal_mode 0)
			)
			(polygon
				(pts
					(xy 316.9158 -120.5738) (xy 316.9158 -120.0658) (xy 316.5348 -120.0658) (xy 316.5348 -120.5738)
				)
			)
		)
	)
	(footprint ""
		(layer "B.Cu")
		(at 351.86112 -90.639392 -90)
		(property "Reference" "R3N23"
			(at 0 0 90)
			(layer "B.SilkS")
			(hide yes)
			(effects
				(font
					(size 1.27 1.27)
				)
				(justify mirror)
			)
		)
		(property "Value" ""
			(at 0 0 90)
			(layer "B.Fab")
			(effects
				(font
					(size 1.27 1.27)
				)
				(justify mirror)
			)
		)
		(duplicate_pad_numbers_are_jumpers no)
		(fp_poly
			(pts
				(xy 0.2794 -0.1016) (xy -0.2794 -0.1016) (xy -0.2794 0.9906) (xy 0.2794 0.9906)
			)
			(stroke
				(width 0)
				(type default)
			)
			(fill no)
			(layer "B.CrtYd")
		)
		(fp_line
			(start -0.2794 0.9906)
			(end -0.2794 -0.1016)
			(stroke
				(width 0.1)
				(type default)
			)
			(layer "B.Fab")
		)
		(fp_line
			(start 0.2794 0.9906)
			(end -0.2794 0.9906)
			(stroke
				(width 0.1)
				(type default)
			)
			(layer "B.Fab")
		)
		(fp_line
			(start -0.2794 -0.1016)
			(end 0.2794 -0.1016)
			(stroke
				(width 0.1)
				(type default)
			)
			(layer "B.Fab")
		)
		(fp_line
			(start 0.2794 -0.1016)
			(end 0.2794 0.9906)
			(stroke
				(width 0.1)
				(type default)
			)
			(layer "B.Fab")
		)
		(pad "1" smd rect
			(at 0 0 90)
			(size 0.508 0.508)
			(layers "B.Cu" "B.Mask" "B.Paste")
			(net "P3V3_STBY")
		)
		(pad "2" smd rect
			(at 0 0.889 90)
			(size 0.508 0.508)
			(layers "B.Cu" "B.Mask" "B.Paste")
			(net "PU_VR_PVCCIO_CPU0_FAULT1")
		)
		(zone
			(layer "B.Cu")
			(hatch none 0.5)
			(connect_pads
				(clearance 0)
			)
			(min_thickness 0.25)
			(keepout
				(tracks not_allowed)
				(vias allowed)
				(pads allowed)
				(copperpour not_allowed)
				(footprints allowed)
			)
			(placement
				(enabled no)
				(sheetname "")
			)
			(fill
				(thermal_gap 0.5)
				(thermal_bridge_width 0.5)
				(island_removal_mode 0)
			)
			(polygon
				(pts
					(xy 351.22612 -90.385392) (xy 351.22612 -90.893392) (xy 351.60712 -90.893392) (xy 351.60712 -90.385392)
				)
			)
		)
		(zone
			(layer "B.Cu")
			(hatch none 0.5)
			(connect_pads
				(clearance 0)
			)
			(min_thickness 0.25)
			(keepout
				(tracks allowed)
				(vias not_allowed)
				(pads allowed)
				(copperpour not_allowed)
				(footprints allowed)
			)
			(placement
				(enabled no)
				(sheetname "")
			)
			(fill
				(thermal_gap 0.5)
				(thermal_bridge_width 0.5)
				(island_removal_mode 0)
			)
			(polygon
				(pts
					(xy 351.60712 -90.385392) (xy 351.60712 -90.893392) (xy 351.22612 -90.893392) (xy 351.22612 -90.385392)
				)
			)
		)
	)
	(footprint ""
		(layer "B.Cu")
		(at 368.716814 -124.389642 -90)
		(property "Reference" "C3M36"
			(at 0 0 90)
			(layer "B.SilkS")
			(hide yes)
			(effects
				(font
					(size 1.27 1.27)
				)
				(justify mirror)
			)
		)
		(property "Value" ""
			(at 0 0 90)
			(layer "B.Fab")
			(effects
				(font
					(size 1.27 1.27)
				)
				(justify mirror)
			)
		)
		(duplicate_pad_numbers_are_jumpers no)
		(fp_poly
			(pts
				(xy -0.3048 -0.1016) (xy -0.3048 0.9906) (xy 0.3048 0.9906) (xy 0.3048 -0.1016)
			)
			(stroke
				(width 0)
				(type default)
			)
			(fill no)
			(layer "B.CrtYd")
		)
		(fp_line
			(start -0.3048 0.9906)
			(end -0.3048 -0.1016)
			(stroke
				(width 0.1)
				(type default)
			)
			(layer "B.Fab")
		)
		(fp_line
			(start 0.3048 0.9906)
			(end -0.3048 0.9906)
			(stroke
				(width 0.1)
				(type default)
			)
			(layer "B.Fab")
		)
		(fp_line
			(start -0.3048 -0.1016)
			(end 0.3048 -0.1016)
			(stroke
				(width 0.1)
				(type default)
			)
			(layer "B.Fab")
		)
		(fp_line
			(start 0.3048 -0.1016)
			(end 0.3048 0.9906)
			(stroke
				(width 0.1)
				(type default)
			)
			(layer "B.Fab")
		)
		(pad "1" smd rect
			(at 0 0 90)
			(size 0.508 0.508)
			(layers "B.Cu" "B.Mask" "B.Paste")
			(net "P3E_CPU0_PE1_PCH_R_RXP<9>")
		)
		(pad "2" smd rect
			(at 0 0.889 90)
			(size 0.508 0.508)
			(layers "B.Cu" "B.Mask" "B.Paste")
			(net "P3E_CPU0_PE1_PCH_RXP<9>")
		)
		(zone
			(layer "B.Cu")
			(hatch none 0.5)
			(connect_pads
				(clearance 0)
			)
			(min_thickness 0.25)
			(keepout
				(tracks not_allowed)
				(vias allowed)
				(pads allowed)
				(copperpour not_allowed)
				(footprints allowed)
			)
			(placement
				(enabled no)
				(sheetname "")
			)
			(fill
				(thermal_gap 0.5)
				(thermal_bridge_width 0.5)
				(island_removal_mode 0)
			)
			(polygon
				(pts
					(xy 368.081814 -124.135642) (xy 368.081814 -124.643642) (xy 368.462814 -124.643642) (xy 368.462814 -124.135642)
				)
			)
		)
		(zone
			(layer "B.Cu")
			(hatch none 0.5)
			(connect_pads
				(clearance 0)
			)
			(min_thickness 0.25)
			(keepout
				(tracks allowed)
				(vias not_allowed)
				(pads allowed)
				(copperpour not_allowed)
				(footprints allowed)
			)
			(placement
				(enabled no)
				(sheetname "")
			)
			(fill
				(thermal_gap 0.5)
				(thermal_bridge_width 0.5)
				(island_removal_mode 0)
			)
			(polygon
				(pts
					(xy 368.462814 -124.135642) (xy 368.462814 -124.643642) (xy 368.081814 -124.643642) (xy 368.081814 -124.135642)
				)
			)
		)
	)
	(footprint ""
		(layer "B.Cu")
		(at 321.2338 -124.115322 180)
		(property "Reference" "C7E2"
			(at 0 0 0)
			(layer "B.SilkS")
			(hide yes)
			(effects
				(font
					(size 1.27 1.27)
				)
				(justify mirror)
			)
		)
		(property "Value" ""
			(at 0 0 0)
			(layer "B.Fab")
			(effects
				(font
					(size 1.27 1.27)
				)
				(justify mirror)
			)
		)
		(duplicate_pad_numbers_are_jumpers no)
		(fp_poly
			(pts
				(xy -0.3048 -0.1016) (xy -0.3048 0.9906) (xy 0.3048 0.9906) (xy 0.3048 -0.1016)
			)
			(stroke
				(width 0)
				(type default)
			)
			(fill no)
			(layer "B.CrtYd")
		)
		(fp_line
			(start 0.3048 0.9906)
			(end -0.3048 0.9906)
			(stroke
				(width 0.1)
				(type default)
			)
			(layer "B.Fab")
		)
		(fp_line
			(start 0.3048 -0.1016)
			(end 0.3048 0.9906)
			(stroke
				(width 0.1)
				(type default)
			)
			(layer "B.Fab")
		)
		(fp_line
			(start -0.3048 0.9906)
			(end -0.3048 -0.1016)
			(stroke
				(width 0.1)
				(type default)
			)
			(layer "B.Fab")
		)
		(fp_line
			(start -0.3048 -0.1016)
			(end 0.3048 -0.1016)
			(stroke
				(width 0.1)
				(type default)
			)
			(layer "B.Fab")
		)
		(pad "1" smd rect
			(at 0 0)
			(size 0.508 0.508)
			(layers "B.Cu" "B.Mask" "B.Paste")
			(net "PVPP_DEF")
		)
		(pad "2" smd rect
			(at 0 0.889)
			(size 0.508 0.508)
			(layers "B.Cu" "B.Mask" "B.Paste")
			(net "GND")
		)
		(zone
			(layer "B.Cu")
			(hatch none 0.5)
			(connect_pads
				(clearance 0)
			)
			(min_thickness 0.25)
			(keepout
				(tracks not_allowed)
				(vias allowed)
				(pads allowed)
				(copperpour not_allowed)
				(footprints allowed)
			)
			(placement
				(enabled no)
				(sheetname "")
			)
			(fill
				(thermal_gap 0.5)
				(thermal_bridge_width 0.5)
				(island_removal_mode 0)
			)
			(polygon
				(pts
					(xy 320.9798 -124.750322) (xy 321.4878 -124.750322) (xy 321.4878 -124.369322) (xy 320.9798 -124.369322)
				)
			)
		)
		(zone
			(layer "B.Cu")
			(hatch none 0.5)
			(connect_pads
				(clearance 0)
			)
			(min_thickness 0.25)
			(keepout
				(tracks allowed)
				(vias not_allowed)
				(pads allowed)
				(copperpour not_allowed)
				(footprints allowed)
			)
			(placement
				(enabled no)
				(sheetname "")
			)
			(fill
				(thermal_gap 0.5)
				(thermal_bridge_width 0.5)
				(island_removal_mode 0)
			)
			(polygon
				(pts
					(xy 320.9798 -124.369322) (xy 321.4878 -124.369322) (xy 321.4878 -124.750322) (xy 320.9798 -124.750322)
				)
			)
		)
	)
	(footprint ""
		(layer "B.Cu")
		(at 409.884118 -90.193114 180)
		(property "Reference" "Q7E1"
			(at -0.11938 -0.97663 180)
			(unlocked yes)
			(layer "B.SilkS")
			(effects
				(font
					(size 0.7874 0.5842)
					(thickness 0.1524)
				)
				(justify left mirror)
			)
		)
		(property "Value" ""
			(at 0 0 0)
			(layer "B.Fab")
			(effects
				(font
					(size 1.27 1.27)
				)
				(justify mirror)
			)
		)
		(duplicate_pad_numbers_are_jumpers no)
		(fp_circle
			(center 0.508 -0.7874)
			(end 0.381 -0.7874)
			(stroke
				(width 0.254)
				(type default)
			)
			(fill no)
			(layer "B.SilkS")
		)
		(fp_poly
			(pts
				(xy -0.2159 1.7526) (xy -1.5621 1.7526) (xy -1.5621 -0.4572) (xy -0.2159 -0.4572)
			)
			(stroke
				(width 0)
				(type default)
			)
			(fill no)
			(layer "B.CrtYd")
		)
		(fp_line
			(start -0.2159 1.75514)
			(end -1.5621 1.75514)
			(stroke
				(width 0.1)
				(type default)
			)
			(layer "B.Fab")
		)
		(fp_line
			(start -0.2159 -0.45466)
			(end -0.2159 1.75514)
			(stroke
				(width 0.1)
				(type default)
			)
			(layer "B.Fab")
		)
		(fp_line
			(start -1.5621 1.75514)
			(end -1.5621 -0.45466)
			(stroke
				(width 0.1)
				(type default)
			)
			(layer "B.Fab")
		)
		(fp_line
			(start -1.5621 -0.45466)
			(end -0.2159 -0.45466)
			(stroke
				(width 0.1)
				(type default)
			)
			(layer "B.Fab")
		)
		(fp_circle
			(center 0.508 -0.7874)
			(end 0.381 -0.7874)
			(stroke
				(width 0.254)
				(type default)
			)
			(fill no)
			(layer "B.Fab")
		)
		(pad "1" smd rect
			(at 0 0)
			(size 1.016 0.381)
			(layers "B.Cu" "B.Mask" "B.Paste")
			(net "GND")
		)
		(pad "2" smd rect
			(at 0 0.65024)
			(size 1.016 0.381)
			(layers "B.Cu" "B.Mask" "B.Paste")
			(net "IRQ_PVDDQ_DEF_VRHOT_LVT3_N")
		)
		(pad "3" smd rect
			(at 0 1.30048)
			(size 1.016 0.381)
			(layers "B.Cu" "B.Mask" "B.Paste")
			(net "H_CPU0_MEMDEF_MEMHOT_G_N")
		)
		(pad "4" smd rect
			(at -1.778 1.30048)
			(size 1.016 0.381)
			(layers "B.Cu" "B.Mask" "B.Paste")
			(net "GND")
		)
		(pad "5" smd rect
			(at -1.778 0.65024)
			(size 1.016 0.381)
			(layers "B.Cu" "B.Mask" "B.Paste")
			(net "H_CPU0_MEMDEF_MEMHOT")
		)
		(pad "6" smd rect
			(at -1.778 0)
			(size 1.016 0.381)
			(layers "B.Cu" "B.Mask" "B.Paste")
			(net "H_CPU0_MEMDEF_MEMHOT")
		)
		(zone
			(layer "B.Cu")
			(hatch none 0.5)
			(connect_pads
				(clearance 0)
			)
			(min_thickness 0.25)
			(keepout
				(tracks allowed)
				(vias not_allowed)
				(pads allowed)
				(copperpour not_allowed)
				(footprints allowed)
			)
			(placement
				(enabled no)
				(sheetname "")
			)
			(fill
				(thermal_gap 0.5)
				(thermal_bridge_width 0.5)
				(island_removal_mode 0)
			)
			(polygon
				(pts
					(xy 409.376118 -90.002614) (xy 410.392118 -90.002614) (xy 410.392118 -91.691714) (xy 409.376118 -91.691714)
				)
			)
		)
		(zone
			(layer "B.Cu")
			(hatch none 0.5)
			(connect_pads
				(clearance 0)
			)
			(min_thickness 0.25)
			(keepout
				(tracks allowed)
				(vias not_allowed)
				(pads allowed)
				(copperpour not_allowed)
				(footprints allowed)
			)
			(placement
				(enabled no)
				(sheetname "")
			)
			(fill
				(thermal_gap 0.5)
				(thermal_bridge_width 0.5)
				(island_removal_mode 0)
			)
			(polygon
				(pts
					(xy 411.154118 -90.002614) (xy 412.170118 -90.002614) (xy 412.170118 -91.691714) (xy 411.154118 -91.691714)
				)
			)
		)
	)
	(footprint ""
		(layer "B.Cu")
		(at 195.2752 -64.008 90)
		(property "Reference" "CT4"
			(at 0.8382 -0.84963 90)
			(unlocked yes)
			(layer "B.SilkS")
			(effects
				(font
					(size 0.7874 0.5842)
					(thickness 0.1524)
				)
				(justify left mirror)
			)
		)
		(property "Value" ""
			(at 0 0 90)
			(layer "B.Fab")
			(effects
				(font
					(size 1.27 1.27)
				)
				(justify mirror)
			)
		)
		(duplicate_pad_numbers_are_jumpers no)
		(fp_poly
			(pts
				(xy -0.3048 -0.1016) (xy -0.3048 0.9906) (xy 0.3048 0.9906) (xy 0.3048 -0.1016)
			)
			(stroke
				(width 0)
				(type default)
			)
			(fill no)
			(layer "B.CrtYd")
		)
		(fp_line
			(start 0.3048 -0.1016)
			(end 0.3048 0.9906)
			(stroke
				(width 0.1)
				(type default)
			)
			(layer "B.Fab")
		)
		(fp_line
			(start -0.3048 -0.1016)
			(end 0.3048 -0.1016)
			(stroke
				(width 0.1)
				(type default)
			)
			(layer "B.Fab")
		)
		(fp_line
			(start 0.3048 0.9906)
			(end -0.3048 0.9906)
			(stroke
				(width 0.1)
				(type default)
			)
			(layer "B.Fab")
		)
		(fp_line
			(start -0.3048 0.9906)
			(end -0.3048 -0.1016)
			(stroke
				(width 0.1)
				(type default)
			)
			(layer "B.Fab")
		)
		(pad "1" smd rect
			(at 0 0 270)
			(size 0.508 0.508)
			(layers "B.Cu" "B.Mask" "B.Paste")
			(net "A_TSENSE_PVCCIN_CPU0")
		)
		(pad "2" smd rect
			(at 0 0.889 270)
			(size 0.508 0.508)
			(layers "B.Cu" "B.Mask" "B.Paste")
			(net "GND")
		)
		(zone
			(layer "B.Cu")
			(hatch none 0.5)
			(connect_pads
				(clearance 0)
			)
			(min_thickness 0.25)
			(keepout
				(tracks allowed)
				(vias not_allowed)
				(pads allowed)
				(copperpour not_allowed)
				(footprints allowed)
			)
			(placement
				(enabled no)
				(sheetname "")
			)
			(fill
				(thermal_gap 0.5)
				(thermal_bridge_width 0.5)
				(island_removal_mode 0)
			)
			(polygon
				(pts
					(xy 195.5292 -64.262) (xy 195.5292 -63.754) (xy 195.9102 -63.754) (xy 195.9102 -64.262)
				)
			)
		)
		(zone
			(layer "B.Cu")
			(hatch none 0.5)
			(connect_pads
				(clearance 0)
			)
			(min_thickness 0.25)
			(keepout
				(tracks not_allowed)
				(vias allowed)
				(pads allowed)
				(copperpour not_allowed)
				(footprints allowed)
			)
			(placement
				(enabled no)
				(sheetname "")
			)
			(fill
				(thermal_gap 0.5)
				(thermal_bridge_width 0.5)
				(island_removal_mode 0)
			)
			(polygon
				(pts
					(xy 195.9102 -64.262) (xy 195.9102 -63.754) (xy 195.5292 -63.754) (xy 195.5292 -64.262)
				)
			)
		)
	)
)
